# T6G (Grand Teton) — schematic netlist excerpt (pin names and nets, part order shuffled) for the footprints in the layout excerpt that follows; sources: Cadence DE-HDL packaged netlist, KiCad conversion of 04192023_DAF0TMB3IC0_F0TG_MB_C_brd_V02_OCP.brd

PC127  Q_CAP  0.1UF 25V 10% X7R  pkg 0402  page 192 : A = PVDD_33_S5_REF ; B = GND
PC6619  Q_CAPP  100UF 16V 20% OSCON  pkg SMLF  page 365 : A = SW_P12V_AUX_P0V9_RETIMER_CPU1_FLT ; B = GND

(kicad_pcb
	(version 20260206)
	(generator "pcbnew")
	(generator_version "10.0")
	(general
		(thickness 1.6)
		(legacy_teardrops no)
	)
	(paper "A4")
	(title_block
		(title "04192023_DAF0TMB3IC0_F0TG_MB_C_brd_V02_OCP.brd")
		(comment 1 "Grand Teton / footprints 1007-1008 of 8354")
	)
	(layers
		(0 "F.Cu" signal "TOP")
		(4 "In1.Cu" signal "GND")
		(6 "In2.Cu" signal "IN1")
		(8 "In3.Cu" signal "GND1")
		(10 "In4.Cu" signal "IN2")
		(12 "In5.Cu" signal "GND2")
		(14 "In6.Cu" signal "IN3")
		(16 "In7.Cu" signal "GND3")
		(18 "In8.Cu" signal "VCC")
		(20 "In9.Cu" signal "VCC1")
		(22 "In10.Cu" signal "GND4")
		(24 "In11.Cu" signal "IN4")
		(26 "In12.Cu" signal "GND5")
		(28 "In13.Cu" signal "IN5")
		(30 "In14.Cu" signal "GND6")
		(32 "In15.Cu" signal "IN6")
		(34 "In16.Cu" signal "GND7")
		(2 "B.Cu" signal "BOTTOM")
		(9 "F.Adhes" user "F.Adhesive")
		(11 "B.Adhes" user "B.Adhesive")
		(13 "F.Paste" user "Package Geometry/Pastemask Top")
		(15 "B.Paste" user "Package Geometry/Pastemask Bottom")
		(5 "F.SilkS" user "Ref Des/Silkscreen Top")
		(7 "B.SilkS" user "Ref Des/Silkscreen Bottom")
		(1 "F.Mask" user "Board Geometry/Soldermask Top")
		(3 "B.Mask" user "Board Geometry/Soldermask Bottom")
		(17 "Dwgs.User" user "User.Drawings")
		(19 "Cmts.User" user "User.Comments")
		(21 "Eco1.User" user "User.Eco1")
		(23 "Eco2.User" user "User.Eco2")
		(25 "Edge.Cuts" user "Board Geometry/Outline")
		(27 "Margin" user)
		(31 "F.CrtYd" user "Package Geometry/Place Bound Top")
		(29 "B.CrtYd" user "Package Geometry/Place Bound Bottom")
		(35 "F.Fab" user "Ref Des/Assembly Top")
		(33 "B.Fab" user "Ref Des/Assembly Bottom")
	)
	(footprint ""
		(layer "F.Cu")
		(at 204.689456 -340.553548)
		(property "Reference" "PC127"
			(at 0 0 0)
			(layer "F.SilkS")
			(hide yes)
			(effects
				(font
					(size 1.27 1.27)
				)
			)
		)
		(property "Value" ""
			(at 0 0 0)
			(layer "F.Fab")
			(effects
				(font
					(size 1.27 1.27)
				)
			)
		)
		(duplicate_pad_numbers_are_jumpers no)
		(fp_line
			(start -0.7874 -0.4064)
			(end 0.7874 -0.4064)
			(stroke
				(width 0.1524)
				(type default)
			)
			(layer "F.SilkS")
		)
		(fp_line
			(start -0.7874 0.4064)
			(end -0.7874 -0.4064)
			(stroke
				(width 0.1524)
				(type default)
			)
			(layer "F.SilkS")
		)
		(fp_line
			(start 0.7874 -0.4064)
			(end 0.7874 0.4064)
			(stroke
				(width 0.1524)
				(type default)
			)
			(layer "F.SilkS")
		)
		(fp_line
			(start 0.7874 0.4064)
			(end -0.7874 0.4064)
			(stroke
				(width 0.1524)
				(type default)
			)
			(layer "F.SilkS")
		)
		(fp_line
			(start -0.67945 -0.305054)
			(end -0.12065 -0.305054)
			(stroke
				(width 0.1)
				(type default)
			)
			(layer "F.Fab")
		)
		(fp_line
			(start -0.67945 0.3048)
			(end -0.67945 -0.305054)
			(stroke
				(width 0.1)
				(type default)
			)
			(layer "F.Fab")
		)
		(fp_line
			(start -0.12065 -0.305054)
			(end -0.12065 -0.2794)
			(stroke
				(width 0.1)
				(type default)
			)
			(layer "F.Fab")
		)
		(fp_line
			(start -0.12065 -0.2794)
			(end 0.12065 -0.2794)
			(stroke
				(width 0.1)
				(type default)
			)
			(layer "F.Fab")
		)
		(fp_line
			(start -0.12065 0.2794)
			(end -0.12065 0.3048)
			(stroke
				(width 0.1)
				(type default)
			)
			(layer "F.Fab")
		)
		(fp_line
			(start -0.12065 0.3048)
			(end -0.67945 0.3048)
			(stroke
				(width 0.1)
				(type default)
			)
			(layer "F.Fab")
		)
		(fp_line
			(start 0.120396 0.2794)
			(end -0.12065 0.2794)
			(stroke
				(width 0.1)
				(type default)
			)
			(layer "F.Fab")
		)
		(fp_line
			(start 0.120396 0.3048)
			(end 0.120396 0.2794)
			(stroke
				(width 0.1)
				(type default)
			)
			(layer "F.Fab")
		)
		(fp_line
			(start 0.12065 -0.3048)
			(end 0.67945 -0.3048)
			(stroke
				(width 0.1)
				(type default)
			)
			(layer "F.Fab")
		)
		(fp_line
			(start 0.12065 -0.2794)
			(end 0.12065 -0.3048)
			(stroke
				(width 0.1)
				(type default)
			)
			(layer "F.Fab")
		)
		(fp_line
			(start 0.67945 -0.3048)
			(end 0.67945 0.3048)
			(stroke
				(width 0.1)
				(type default)
			)
			(layer "F.Fab")
		)
		(fp_line
			(start 0.67945 0.3048)
			(end 0.120396 0.3048)
			(stroke
				(width 0.1)
				(type default)
			)
			(layer "F.Fab")
		)
		(pad "1" smd circle
			(at -0.40005 0)
			(size 0 0)
			(layers "F.Cu" "F.Mask" "F.Paste")
			(net "PVDD_33_S5_REF")
		)
		(pad "2" smd circle
			(at 0.40005 0)
			(size 0 0)
			(layers "F.Cu" "F.Mask" "F.Paste")
			(net "GND")
		)
	)
	(footprint ""
		(layer "F.Cu")
		(at 18.158968 -400.099276 180)
		(property "Reference" "PC6619"
			(at 8.887968 0.051054 0)
			(unlocked yes)
			(layer "F.SilkS")
			(effects
				(font
					(size 0.7874 0.5842)
					(thickness 0.1524)
				)
				(justify left)
			)
		)
		(property "Value" ""
			(at 0 0 180)
			(layer "F.Fab")
			(effects
				(font
					(size 1.27 1.27)
				)
			)
		)
		(duplicate_pad_numbers_are_jumpers no)
		(fp_line
			(start 2.750058 2.750058)
			(end 2.750058 0.9398)
			(stroke
				(width 0.1524)
				(type default)
			)
			(layer "F.SilkS")
		)
		(fp_line
			(start 2.750058 -0.9398)
			(end 2.750058 -2.750058)
			(stroke
				(width 0.1524)
				(type default)
			)
			(layer "F.SilkS")
		)
		(fp_line
			(start 2.750058 -2.750058)
			(end -1.988058 -2.750058)
			(stroke
				(width 0.1524)
				(type default)
			)
			(layer "F.SilkS")
		)
		(fp_line
			(start -1.988058 2.750058)
			(end 2.750058 2.750058)
			(stroke
				(width 0.1524)
				(type default)
			)
			(layer "F.SilkS")
		)
		(fp_line
			(start -1.988058 -2.750058)
			(end -2.750058 -1.988058)
			(stroke
				(width 0.1524)
				(type default)
			)
			(layer "F.SilkS")
		)
		(fp_line
			(start -2.750058 1.988058)
			(end -1.988058 2.750058)
			(stroke
				(width 0.1524)
				(type default)
			)
			(layer "F.SilkS")
		)
		(fp_line
			(start -2.750058 0.9398)
			(end -2.750058 1.988058)
			(stroke
				(width 0.1524)
				(type default)
			)
			(layer "F.SilkS")
		)
		(fp_line
			(start -2.750058 -1.988058)
			(end -2.750058 -0.9398)
			(stroke
				(width 0.1524)
				(type default)
			)
			(layer "F.SilkS")
		)
		(fp_line
			(start 2.750058 2.750058)
			(end 2.750058 -2.750058)
			(stroke
				(width 0.1)
				(type default)
			)
			(layer "F.Fab")
		)
		(fp_line
			(start 2.750058 -2.750058)
			(end -2.750058 -2.750058)
			(stroke
				(width 0.1)
				(type default)
			)
			(layer "F.Fab")
		)
		(fp_line
			(start -2.750058 2.750058)
			(end 2.750058 2.750058)
			(stroke
				(width 0.1)
				(type default)
			)
			(layer "F.Fab")
		)
		(fp_line
			(start -2.750058 -2.750058)
			(end -2.750058 2.750058)
			(stroke
				(width 0.1)
				(type default)
			)
			(layer "F.Fab")
		)
		(pad "1" smd rect
			(at -2.199894 0 270)
			(size 1.6002 3.0226)
			(layers "F.Cu" "F.Mask" "F.Paste")
			(net "SW_P12V_AUX_P0V9_RETIMER_CPU1_FLT")
		)
		(pad "2" smd rect
			(at 2.199894 0 270)
			(size 1.6002 3.0226)
			(layers "F.Cu" "F.Mask" "F.Paste")
			(net "GND")
		)
	)
)
